FILE_TYPE=LIBRARY_PARTS;
primitive 'RAA229620GNPHA0';
  pin
    'CS11':
      PIN_NUMBER='(27)';
      INPUT_LOAD='(-0.01,0.01)';
    'VCC':
      PIN_NUMBER='(47)';
      PINUSE='POWER';
      NO_LOAD_CHECK='Both';
      NO_IO_CHECK='Both';
      NO_ASSERT_CHECK='TRUE';
      NO_DIR_CHECK='TRUE';
      ALLOW_CONNECT='TRUE';
    'SVTI':
      PIN_NUMBER='(24)';
      INPUT_LOAD='(-0.01,0.01)';
    'PMSCL':
      PIN_NUMBER='(14)';
      INPUT_LOAD='(-0.01,0.01)';
    'SVC':
      PIN_NUMBER='(22)';
      INPUT_LOAD='(-0.01,0.01)';
    'CS6':
      PIN_NUMBER='(32)';
      INPUT_LOAD='(-0.01,0.01)';
    'SVTO':
      PIN_NUMBER='(23)';
      OUTPUT_LOAD='(1.0,-1.0)';
    'RESET_L':
      PIN_NUMBER='(18)';
      INPUT_LOAD='(-0.01,0.01)';
    'CS5':
      PIN_NUMBER='(33)';
      INPUT_LOAD='(-0.01,0.01)';
    'CS4':
      PIN_NUMBER='(34)';
      INPUT_LOAD='(-0.01,0.01)';
    'PG1':
      PIN_NUMBER='(20)';
      OUTPUT_LOAD='(1.0,-1.0)';
    'SVD':
      PIN_NUMBER='(21)';
      INPUT_LOAD='(-0.01,0.01)';
    'NPMALERT':
      PIN_NUMBER='(15)';
      OUTPUT_LOAD='(1.0,-1.0)';
    'EN0':
      PIN_NUMBER='(17)';
      INPUT_LOAD='(-0.01,0.01)';
    'RGND0':
      PIN_NUMBER='(26)';
      INPUT_LOAD='(-0.01,0.01)';
    'PMSDA':
      PIN_NUMBER='(13)';
      BIDIRECTIONAL='TRUE';
      INPUT_LOAD='(-0.01,0.01)';
      OUTPUT_LOAD='(1.0,-1.0)';
    'PWM4':
      PIN_NUMBER='(5)';
      OUTPUT_LOAD='(1.0,-1.0)';
    'PWM5':
      PIN_NUMBER='(6)';
      OUTPUT_LOAD='(1.0,-1.0)';
    'VSEN0':
      PIN_NUMBER='(25)';
      INPUT_LOAD='(-0.01,0.01)';
    'PWM1':
      PIN_NUMBER='(2)';
      OUTPUT_LOAD='(1.0,-1.0)';
    'PG0':
      PIN_NUMBER='(16)';
      OUTPUT_LOAD='(1.0,-1.0)';
    'PWM6':
      PIN_NUMBER='(7)';
      OUTPUT_LOAD='(1.0,-1.0)';
    'VCCS':
      PIN_NUMBER='(48)';
      PINUSE='POWER';
      NO_LOAD_CHECK='Both';
      NO_IO_CHECK='Both';
      NO_ASSERT_CHECK='TRUE';
      NO_DIR_CHECK='TRUE';
      ALLOW_CONNECT='TRUE';
    'VMON||IINSEN':
      PIN_NUMBER='(45)';
      BIDIRECTIONAL='TRUE';
      INPUT_LOAD='(-0.01,0.01)';
      OUTPUT_LOAD='(1.0,-1.0)';
    'VINSEN':
      PIN_NUMBER='(46)';
      INPUT_LOAD='(-0.01,0.01)';
    'TEMP0':
      PIN_NUMBER='(44)';
      INPUT_LOAD='(-0.01,0.01)';
    'VDDIO':
      PIN_NUMBER='(19)';
      PINUSE='POWER';
      NO_LOAD_CHECK='Both';
      NO_IO_CHECK='Both';
      NO_ASSERT_CHECK='TRUE';
      NO_DIR_CHECK='TRUE';
      ALLOW_CONNECT='TRUE';
    'VSEN1':
      PIN_NUMBER='(40)';
      INPUT_LOAD='(-0.01,0.01)';
    'RGND1':
      PIN_NUMBER='(39)';
      INPUT_LOAD='(-0.01,0.01)';
    'CS1':
      PIN_NUMBER='(37)';
      INPUT_LOAD='(-0.01,0.01)';
    'PWM11':
      PIN_NUMBER='(12)';
      OUTPUT_LOAD='(1.0,-1.0)';
    'PWM3':
      PIN_NUMBER='(4)';
      OUTPUT_LOAD='(1.0,-1.0)';
    'CS3':
      PIN_NUMBER='(35)';
      INPUT_LOAD='(-0.01,0.01)';
    'PWM2':
      PIN_NUMBER='(3)';
      OUTPUT_LOAD='(1.0,-1.0)';
    'CS2':
      PIN_NUMBER='(36)';
      INPUT_LOAD='(-0.01,0.01)';
    'OCP_L':
      PIN_NUMBER='(41)';
      OUTPUT_LOAD='(1.0,-1.0)';
    'TH_GND':
      PIN_NUMBER='(TH)';
      PINUSE='POWER';
      NO_LOAD_CHECK='Both';
      NO_IO_CHECK='Both';
      NO_ASSERT_CHECK='TRUE';
      NO_DIR_CHECK='TRUE';
      ALLOW_CONNECT='TRUE';
    'EN1||ADDR_CFG':
      PIN_NUMBER='(42)';
      INPUT_LOAD='(-0.01,0.01)';
    'TEMP1':
      PIN_NUMBER='(43)';
      INPUT_LOAD='(-0.01,0.01)';
    'PWM0':
      PIN_NUMBER='(1)';
      OUTPUT_LOAD='(1.0,-1.0)';
    'CS0':
      PIN_NUMBER='(38)';
      INPUT_LOAD='(-0.01,0.01)';
    'PWM7':
      PIN_NUMBER='(8)';
      OUTPUT_LOAD='(1.0,-1.0)';
    'CS7':
      PIN_NUMBER='(31)';
      INPUT_LOAD='(-0.01,0.01)';
    'PWM8':
      PIN_NUMBER='(9)';
      OUTPUT_LOAD='(1.0,-1.0)';
    'CS8':
      PIN_NUMBER='(30)';
      INPUT_LOAD='(-0.01,0.01)';
    'PWM9':
      PIN_NUMBER='(10)';
      OUTPUT_LOAD='(1.0,-1.0)';
    'CS9':
      PIN_NUMBER='(29)';
      INPUT_LOAD='(-0.01,0.01)';
    'PWM10':
      PIN_NUMBER='(11)';
      OUTPUT_LOAD='(1.0,-1.0)';
    'CS10':
      PIN_NUMBER='(28)';
      INPUT_LOAD='(-0.01,0.01)';
  end_pin;
  body
    PART_NAME='RAA229620GNPHA0';
    BODY_NAME='RAA229620GNPHA0';
    PHYS_DES_PREFIX='U';
    CLASS='IC';
  end_body;
end_primitive;

END.
